(kicad_pcb
	(version 20260206)
	(generator "pcbnew")
	(generator_version "10.0")
	(general
		(thickness 1.6)
		(legacy_teardrops no)
	)
	(paper "A4")
	(title_block
		(title "01162023_DA0F0TEBIF0_F0T_Expander_BD_F_brd_V02_OCP.brd")
		(comment 1 "Grand Teton / footprints 5593-5598 of 9728")
	)
	(layers
		(0 "F.Cu" signal "TOP")
		(4 "In1.Cu" signal "GND")
		(6 "In2.Cu" signal "VCC")
		(8 "In3.Cu" signal "VCC1")
		(10 "In4.Cu" signal "GND1")
		(12 "In5.Cu" signal "IN1")
		(14 "In6.Cu" signal "GND2")
		(16 "In7.Cu" signal "IN2")
		(18 "In8.Cu" signal "GND3")
		(20 "In9.Cu" signal "IN3")
		(22 "In10.Cu" signal "GND4")
		(24 "In11.Cu" signal "IN4")
		(26 "In12.Cu" signal "GND5")
		(28 "In13.Cu" signal "IN5")
		(30 "In14.Cu" signal "GND6")
		(32 "In15.Cu" signal "IN6")
		(34 "In16.Cu" signal "GND7")
		(2 "B.Cu" signal "BOTTOM")
		(9 "F.Adhes" user "F.Adhesive")
		(11 "B.Adhes" user "B.Adhesive")
		(13 "F.Paste" user "Package Geometry/Pastemask Top")
		(15 "B.Paste" user "Package Geometry/Pastemask Bottom")
		(5 "F.SilkS" user "Ref Des/Silkscreen Top")
		(7 "B.SilkS" user "Ref Des/Silkscreen Bottom")
		(1 "F.Mask" user "Board Geometry/Soldermask Top")
		(3 "B.Mask" user "Board Geometry/Soldermask Bottom")
		(17 "Dwgs.User" user "User.Drawings")
		(19 "Cmts.User" user "User.Comments")
		(21 "Eco1.User" user "User.Eco1")
		(23 "Eco2.User" user "User.Eco2")
		(25 "Edge.Cuts" user "Board Geometry/Outline")
		(27 "Margin" user)
		(31 "F.CrtYd" user "Package Geometry/Place Bound Top")
		(29 "B.CrtYd" user "Package Geometry/Place Bound Bottom")
		(35 "F.Fab" user "Ref Des/Assembly Top")
		(33 "B.Fab" user "Ref Des/Assembly Bottom")
	)
	(footprint ""
		(layer "F.Cu")
		(at 117.175026 -309.749952 -90)
		(property "Reference" "R6454"
			(at 0 0 270)
			(layer "F.SilkS")
			(hide yes)
			(effects
				(font
					(size 1.27 1.27)
				)
			)
		)
		(property "Value" ""
			(at 0 0 270)
			(layer "F.Fab")
			(effects
				(font
					(size 1.27 1.27)
				)
			)
		)
		(duplicate_pad_numbers_are_jumpers no)
		(fp_line
			(start -0.7874 0.4064)
			(end -0.7874 -0.4064)
			(stroke
				(width 0.1524)
				(type default)
			)
			(layer "F.SilkS")
		)
		(fp_line
			(start 0.7874 0.4064)
			(end -0.7874 0.4064)
			(stroke
				(width 0.1524)
				(type default)
			)
			(layer "F.SilkS")
		)
		(fp_line
			(start -0.7874 -0.4064)
			(end 0.7874 -0.4064)
			(stroke
				(width 0.1524)
				(type default)
			)
			(layer "F.SilkS")
		)
		(fp_line
			(start 0.7874 -0.4064)
			(end 0.7874 0.4064)
			(stroke
				(width 0.1524)
				(type default)
			)
			(layer "F.SilkS")
		)
		(fp_line
			(start -0.67945 0.3048)
			(end -0.67945 -0.305054)
			(stroke
				(width 0.1)
				(type default)
			)
			(layer "F.Fab")
		)
		(fp_line
			(start -0.12065 0.3048)
			(end -0.67945 0.3048)
			(stroke
				(width 0.1)
				(type default)
			)
			(layer "F.Fab")
		)
		(fp_line
			(start 0.120396 0.3048)
			(end 0.120396 0.2794)
			(stroke
				(width 0.1)
				(type default)
			)
			(layer "F.Fab")
		)
		(fp_line
			(start 0.67945 0.3048)
			(end 0.120396 0.3048)
			(stroke
				(width 0.1)
				(type default)
			)
			(layer "F.Fab")
		)
		(fp_line
			(start -0.12065 0.2794)
			(end -0.12065 0.3048)
			(stroke
				(width 0.1)
				(type default)
			)
			(layer "F.Fab")
		)
		(fp_line
			(start 0.120396 0.2794)
			(end -0.12065 0.2794)
			(stroke
				(width 0.1)
				(type default)
			)
			(layer "F.Fab")
		)
		(fp_line
			(start -0.12065 -0.2794)
			(end 0.12065 -0.2794)
			(stroke
				(width 0.1)
				(type default)
			)
			(layer "F.Fab")
		)
		(fp_line
			(start 0.12065 -0.2794)
			(end 0.12065 -0.3048)
			(stroke
				(width 0.1)
				(type default)
			)
			(layer "F.Fab")
		)
		(fp_line
			(start 0.12065 -0.3048)
			(end 0.67945 -0.3048)
			(stroke
				(width 0.1)
				(type default)
			)
			(layer "F.Fab")
		)
		(fp_line
			(start 0.67945 -0.3048)
			(end 0.67945 0.3048)
			(stroke
				(width 0.1)
				(type default)
			)
			(layer "F.Fab")
		)
		(fp_line
			(start -0.67945 -0.305054)
			(end -0.12065 -0.305054)
			(stroke
				(width 0.1)
				(type default)
			)
			(layer "F.Fab")
		)
		(fp_line
			(start -0.12065 -0.305054)
			(end -0.12065 -0.2794)
			(stroke
				(width 0.1)
				(type default)
			)
			(layer "F.Fab")
		)
		(pad "1" smd circle
			(at -0.40005 0 270)
			(size 0 0)
			(layers "F.Cu" "F.Mask" "F.Paste")
			(net "P0V8_SERDES_VDDA_PEX0")
		)
		(pad "2" smd circle
			(at 0.40005 0 270)
			(size 0 0)
			(layers "F.Cu" "F.Mask" "F.Paste")
			(net "P0V8_SERDES_VDDA_PEX0_C5")
		)
	)
	(footprint ""
		(layer "F.Cu")
		(at 56.271922 -362.556044 90)
		(property "Reference" "R6733"
			(at 0 0 90)
			(layer "F.SilkS")
			(hide yes)
			(effects
				(font
					(size 1.27 1.27)
				)
			)
		)
		(property "Value" ""
			(at 0 0 90)
			(layer "F.Fab")
			(effects
				(font
					(size 1.27 1.27)
				)
			)
		)
		(duplicate_pad_numbers_are_jumpers no)
		(fp_line
			(start 0.7874 -0.4064)
			(end 0.7874 0.4064)
			(stroke
				(width 0.1524)
				(type default)
			)
			(layer "F.SilkS")
		)
		(fp_line
			(start -0.7874 -0.4064)
			(end 0.037846 -0.4064)
			(stroke
				(width 0.1524)
				(type default)
			)
			(layer "F.SilkS")
		)
		(fp_line
			(start 0.7874 0.4064)
			(end -0.7874 0.4064)
			(stroke
				(width 0.1524)
				(type default)
			)
			(layer "F.SilkS")
		)
		(fp_line
			(start -0.12065 -0.305054)
			(end -0.12065 -0.2794)
			(stroke
				(width 0.1)
				(type default)
			)
			(layer "F.Fab")
		)
		(fp_line
			(start -0.67945 -0.305054)
			(end -0.12065 -0.305054)
			(stroke
				(width 0.1)
				(type default)
			)
			(layer "F.Fab")
		)
		(fp_line
			(start 0.67945 -0.3048)
			(end 0.67945 0.3048)
			(stroke
				(width 0.1)
				(type default)
			)
			(layer "F.Fab")
		)
		(fp_line
			(start 0.12065 -0.3048)
			(end 0.67945 -0.3048)
			(stroke
				(width 0.1)
				(type default)
			)
			(layer "F.Fab")
		)
		(fp_line
			(start 0.12065 -0.2794)
			(end 0.12065 -0.3048)
			(stroke
				(width 0.1)
				(type default)
			)
			(layer "F.Fab")
		)
		(fp_line
			(start -0.12065 -0.2794)
			(end 0.12065 -0.2794)
			(stroke
				(width 0.1)
				(type default)
			)
			(layer "F.Fab")
		)
		(fp_line
			(start 0.120396 0.2794)
			(end -0.12065 0.2794)
			(stroke
				(width 0.1)
				(type default)
			)
			(layer "F.Fab")
		)
		(fp_line
			(start -0.12065 0.2794)
			(end -0.12065 0.3048)
			(stroke
				(width 0.1)
				(type default)
			)
			(layer "F.Fab")
		)
		(fp_line
			(start 0.67945 0.3048)
			(end 0.120396 0.3048)
			(stroke
				(width 0.1)
				(type default)
			)
			(layer "F.Fab")
		)
		(fp_line
			(start 0.120396 0.3048)
			(end 0.120396 0.2794)
			(stroke
				(width 0.1)
				(type default)
			)
			(layer "F.Fab")
		)
		(fp_line
			(start -0.12065 0.3048)
			(end -0.67945 0.3048)
			(stroke
				(width 0.1)
				(type default)
			)
			(layer "F.Fab")
		)
		(fp_line
			(start -0.67945 0.3048)
			(end -0.67945 -0.305054)
			(stroke
				(width 0.1)
				(type default)
			)
			(layer "F.Fab")
		)
		(pad "1" smd rect
			(at -0.40005 0 270)
			(size 0.4572 0.508)
			(layers "F.Cu" "F.Mask" "F.Paste")
			(net "USB2_GPU_HMC_USB8042_DP")
		)
		(pad "2" smd rect
			(at 0.40005 0 270)
			(size 0.4572 0.508)
			(layers "F.Cu" "F.Mask" "F.Paste")
			(net "USB2_GPU_HMC_DP")
		)
	)
	(footprint ""
		(layer "F.Cu")
		(at 203.174854 -373.659654 -90)
		(property "Reference" "R6247"
			(at 0 0 270)
			(layer "F.SilkS")
			(hide yes)
			(effects
				(font
					(size 1.27 1.27)
				)
			)
		)
		(property "Value" ""
			(at 0 0 270)
			(layer "F.Fab")
			(effects
				(font
					(size 1.27 1.27)
				)
			)
		)
		(duplicate_pad_numbers_are_jumpers no)
		(fp_line
			(start -0.7874 0.4064)
			(end -0.7874 -0.4064)
			(stroke
				(width 0.1524)
				(type default)
			)
			(layer "F.SilkS")
		)
		(fp_line
			(start 0.7874 0.4064)
			(end -0.7874 0.4064)
			(stroke
				(width 0.1524)
				(type default)
			)
			(layer "F.SilkS")
		)
		(fp_line
			(start -0.7874 -0.4064)
			(end 0.7874 -0.4064)
			(stroke
				(width 0.1524)
				(type default)
			)
			(layer "F.SilkS")
		)
		(fp_line
			(start 0.7874 -0.4064)
			(end 0.7874 0.4064)
			(stroke
				(width 0.1524)
				(type default)
			)
			(layer "F.SilkS")
		)
		(fp_line
			(start -0.67945 0.3048)
			(end -0.67945 -0.305054)
			(stroke
				(width 0.1)
				(type default)
			)
			(layer "F.Fab")
		)
		(fp_line
			(start -0.12065 0.3048)
			(end -0.67945 0.3048)
			(stroke
				(width 0.1)
				(type default)
			)
			(layer "F.Fab")
		)
		(fp_line
			(start 0.120396 0.3048)
			(end 0.120396 0.2794)
			(stroke
				(width 0.1)
				(type default)
			)
			(layer "F.Fab")
		)
		(fp_line
			(start 0.67945 0.3048)
			(end 0.120396 0.3048)
			(stroke
				(width 0.1)
				(type default)
			)
			(layer "F.Fab")
		)
		(fp_line
			(start -0.12065 0.2794)
			(end -0.12065 0.3048)
			(stroke
				(width 0.1)
				(type default)
			)
			(layer "F.Fab")
		)
		(fp_line
			(start 0.120396 0.2794)
			(end -0.12065 0.2794)
			(stroke
				(width 0.1)
				(type default)
			)
			(layer "F.Fab")
		)
		(fp_line
			(start -0.12065 -0.2794)
			(end 0.12065 -0.2794)
			(stroke
				(width 0.1)
				(type default)
			)
			(layer "F.Fab")
		)
		(fp_line
			(start 0.12065 -0.2794)
			(end 0.12065 -0.3048)
			(stroke
				(width 0.1)
				(type default)
			)
			(layer "F.Fab")
		)
		(fp_line
			(start 0.12065 -0.3048)
			(end 0.67945 -0.3048)
			(stroke
				(width 0.1)
				(type default)
			)
			(layer "F.Fab")
		)
		(fp_line
			(start 0.67945 -0.3048)
			(end 0.67945 0.3048)
			(stroke
				(width 0.1)
				(type default)
			)
			(layer "F.Fab")
		)
		(fp_line
			(start -0.67945 -0.305054)
			(end -0.12065 -0.305054)
			(stroke
				(width 0.1)
				(type default)
			)
			(layer "F.Fab")
		)
		(fp_line
			(start -0.12065 -0.305054)
			(end -0.12065 -0.2794)
			(stroke
				(width 0.1)
				(type default)
			)
			(layer "F.Fab")
		)
		(pad "1" smd circle
			(at -0.40005 0 270)
			(size 0 0)
			(layers "F.Cu" "F.Mask" "F.Paste")
			(net "P3V3_AUX")
		)
		(pad "2" smd circle
			(at 0.40005 0 270)
			(size 0 0)
			(layers "F.Cu" "F.Mask" "F.Paste")
			(net "HSC_ALERT1_N")
		)
	)
	(footprint ""
		(layer "F.Cu")
		(at 171.487592 -350.098614 90)
		(property "Reference" "C392"
			(at 0 0 90)
			(layer "F.SilkS")
			(hide yes)
			(effects
				(font
					(size 1.27 1.27)
				)
			)
		)
		(property "Value" ""
			(at 0 0 90)
			(layer "F.Fab")
			(effects
				(font
					(size 1.27 1.27)
				)
			)
		)
		(duplicate_pad_numbers_are_jumpers no)
		(fp_line
			(start 0.299974 -0.150114)
			(end 0.299974 0.150114)
			(stroke
				(width 0.1)
				(type default)
			)
			(layer "F.Fab")
		)
		(fp_line
			(start -0.299974 -0.150114)
			(end 0.299974 -0.150114)
			(stroke
				(width 0.1)
				(type default)
			)
			(layer "F.Fab")
		)
		(fp_line
			(start 0.299974 0.150114)
			(end -0.299974 0.150114)
			(stroke
				(width 0.1)
				(type default)
			)
			(layer "F.Fab")
		)
		(fp_line
			(start -0.299974 0.150114)
			(end -0.299974 -0.150114)
			(stroke
				(width 0.1)
				(type default)
			)
			(layer "F.Fab")
		)
		(pad "1" smd rect
			(at -0.2667 0 90)
			(size 0.3048 0.381)
			(layers "F.Cu" "F.Mask" "F.Paste")
			(net "P5E_PEX1_STN7_TX_DP<117>")
		)
		(pad "2" smd rect
			(at 0.2667 0 90)
			(size 0.3048 0.381)
			(layers "F.Cu" "F.Mask" "F.Paste")
			(net "P5E_PEX1_STN7_TX_C_DP<117>")
		)
	)
	(footprint ""
		(layer "F.Cu")
		(at 445.933068 -98.968052 -90)
		(property "Reference" "PU29"
			(at 0.75692 2.485136 90)
			(unlocked yes)
			(layer "F.SilkS")
			(effects
				(font
					(size 0.7874 0.5842)
					(thickness 0.1524)
				)
				(justify left)
			)
		)
		(property "Value" ""
			(at 0 0 270)
			(layer "F.Fab")
			(effects
				(font
					(size 1.27 1.27)
				)
			)
		)
		(duplicate_pad_numbers_are_jumpers no)
		(fp_line
			(start -1.943608 1.549908)
			(end -1.943608 -1.549908)
			(stroke
				(width 0.1524)
				(type default)
			)
			(layer "F.SilkS")
		)
		(fp_line
			(start 1.943608 1.549908)
			(end -1.943608 1.549908)
			(stroke
				(width 0.1524)
				(type default)
			)
			(layer "F.SilkS")
		)
		(fp_line
			(start -1.943608 -1.549908)
			(end 1.943608 -1.549908)
			(stroke
				(width 0.1524)
				(type default)
			)
			(layer "F.SilkS")
		)
		(fp_line
			(start 1.943608 -1.549908)
			(end 1.943608 1.549908)
			(stroke
				(width 0.1524)
				(type default)
			)
			(layer "F.SilkS")
		)
		(fp_poly
			(pts
				(xy -2.019808 -1.549908) (xy -1.257808 -1.549908) (xy -1.257808 -1.880108) (xy -2.019808 -1.880108)
			)
			(stroke
				(width 0)
				(type default)
			)
			(fill yes)
			(layer "F.SilkS")
		)
		(fp_line
			(start -1.549908 1.549908)
			(end -1.549908 -1.549908)
			(stroke
				(width 0.1)
				(type default)
			)
			(layer "F.Fab")
		)
		(fp_line
			(start 1.549908 1.549908)
			(end -1.549908 1.549908)
			(stroke
				(width 0.1)
				(type default)
			)
			(layer "F.Fab")
		)
		(fp_line
			(start -1.549908 -1.549908)
			(end 1.549908 -1.549908)
			(stroke
				(width 0.1)
				(type default)
			)
			(layer "F.Fab")
		)
		(fp_line
			(start 1.549908 -1.549908)
			(end 1.549908 1.549908)
			(stroke
				(width 0.1)
				(type default)
			)
			(layer "F.Fab")
		)
		(fp_poly
			(pts
				(xy -2.019808 -1.549908) (xy -1.257808 -1.549908) (xy -1.257808 -1.880108) (xy -2.019808 -1.880108)
			)
			(stroke
				(width 0)
				(type default)
			)
			(fill yes)
			(layer "F.Fab")
		)
		(pad "1" smd rect
			(at -1.500124 -1.249934 180)
			(size 0.2794 0.6096)
			(layers "F.Cu" "F.Mask" "F.Paste")
			(net "P12V_NIC7_R")
		)
		(pad "2" smd rect
			(at -1.500124 -0.750062 180)
			(size 0.2794 0.6096)
			(layers "F.Cu" "F.Mask" "F.Paste")
			(net "P12V_NIC7_R")
		)
		(pad "3" smd rect
			(at -1.500124 -0.249936 180)
			(size 0.2794 0.6096)
			(layers "F.Cu" "F.Mask" "F.Paste")
			(net "P12V_NIC7_R")
		)
		(pad "4" smd rect
			(at -1.500124 0.249936 180)
			(size 0.2794 0.6096)
			(layers "F.Cu" "F.Mask" "F.Paste")
			(net "P12V_NIC7_R")
		)
		(pad "5" smd rect
			(at -1.500124 0.750062 180)
			(size 0.2794 0.6096)
			(layers "F.Cu" "F.Mask" "F.Paste")
			(net "P12V_NIC7_R")
		)
		(pad "6" smd rect
			(at -1.500124 1.249934 180)
			(size 0.2794 0.6096)
			(layers "F.Cu" "F.Mask" "F.Paste")
			(net "GND")
		)
		(pad "7" smd rect
			(at 1.500124 1.249934 180)
			(size 0.2794 0.6096)
			(layers "F.Cu" "F.Mask" "F.Paste")
			(net "P12V_NIC7_SS")
		)
		(pad "8" smd rect
			(at 1.500124 0.750062 180)
			(size 0.2794 0.6096)
			(layers "F.Cu" "F.Mask" "F.Paste")
			(net "PWRGD_P12V_NIC7")
		)
		(pad "9" smd rect
			(at 1.500124 0.249936 180)
			(size 0.2794 0.6096)
			(layers "F.Cu" "F.Mask" "F.Paste")
			(net "P12V_NIC7_OCP")
		)
		(pad "10" smd rect
			(at 1.500124 -0.249936 180)
			(size 0.2794 0.6096)
			(layers "F.Cu" "F.Mask" "F.Paste")
			(net "P5V_AUX")
		)
		(pad "11" smd rect
			(at 1.500124 -0.750062 180)
			(size 0.2794 0.6096)
			(layers "F.Cu" "F.Mask" "F.Paste")
			(net "P12V_NIC7_EN_R")
		)
		(pad "12" smd rect
			(at 1.500124 -1.249934 180)
			(size 0.2794 0.6096)
			(layers "F.Cu" "F.Mask" "F.Paste")
			(net "P12V_AUX")
		)
		(pad "13" smd rect
			(at 0 0 270)
			(size 1.9812 2.7178)
			(layers "F.Cu" "F.Mask" "F.Paste")
			(net "P12V_AUX")
		)
		(zone
			(layer "F.Cu")
			(hatch none 0.5)
			(connect_pads
				(clearance 0)
			)
			(min_thickness 0.25)
			(keepout
				(tracks not_allowed)
				(vias allowed)
				(pads allowed)
				(copperpour not_allowed)
				(footprints allowed)
			)
			(placement
				(enabled no)
				(sheetname "")
			)
			(fill
				(thermal_gap 0.5)
				(thermal_bridge_width 0.5)
				(island_removal_mode 0)
			)
			(polygon
				(pts
					(xy 447.482468 -97.825052) (xy 447.355468 -97.825052) (xy 444.383668 -97.825052) (xy 444.38316 -97.825052)
					(xy 444.38316 -100.111052) (xy 444.383668 -100.111052) (xy 444.510668 -100.111052) (xy 445.933068 -100.111052)
					(xy 445.933068 -100.009452) (xy 444.510668 -100.009452) (xy 444.510668 -97.926652) (xy 447.355468 -97.926652)
					(xy 447.355468 -100.009452) (xy 445.958468 -100.009452) (xy 445.958468 -100.111052) (xy 447.355468 -100.111052)
					(xy 447.482468 -100.111052) (xy 447.482976 -100.111052) (xy 447.482976 -97.825052)
				)
			)
		)
	)
	(footprint ""
		(layer "F.Cu")
		(at 18.638774 -22.867366 90)
		(property "Reference" "C3876"
			(at 0 0 90)
			(layer "F.SilkS")
			(hide yes)
			(effects
				(font
					(size 1.27 1.27)
				)
			)
		)
		(property "Value" ""
			(at 0 0 90)
			(layer "F.Fab")
			(effects
				(font
					(size 1.27 1.27)
				)
			)
		)
		(duplicate_pad_numbers_are_jumpers no)
		(fp_line
			(start 0.7874 -0.4064)
			(end 0.7874 0.4064)
			(stroke
				(width 0.1524)
				(type default)
			)
			(layer "F.SilkS")
		)
		(fp_line
			(start -0.7874 -0.4064)
			(end 0.7874 -0.4064)
			(stroke
				(width 0.1524)
				(type default)
			)
			(layer "F.SilkS")
		)
		(fp_line
			(start 0.7874 0.4064)
			(end -0.7874 0.4064)
			(stroke
				(width 0.1524)
				(type default)
			)
			(layer "F.SilkS")
		)
		(fp_line
			(start -0.7874 0.4064)
			(end -0.7874 -0.4064)
			(stroke
				(width 0.1524)
				(type default)
			)
			(layer "F.SilkS")
		)
		(fp_line
			(start -0.12065 -0.305054)
			(end -0.12065 -0.2794)
			(stroke
				(width 0.1)
				(type default)
			)
			(layer "F.Fab")
		)
		(fp_line
			(start -0.67945 -0.305054)
			(end -0.12065 -0.305054)
			(stroke
				(width 0.1)
				(type default)
			)
			(layer "F.Fab")
		)
		(fp_line
			(start 0.67945 -0.3048)
			(end 0.67945 0.3048)
			(stroke
				(width 0.1)
				(type default)
			)
			(layer "F.Fab")
		)
		(fp_line
			(start 0.12065 -0.3048)
			(end 0.67945 -0.3048)
			(stroke
				(width 0.1)
				(type default)
			)
			(layer "F.Fab")
		)
		(fp_line
			(start 0.12065 -0.2794)
			(end 0.12065 -0.3048)
			(stroke
				(width 0.1)
				(type default)
			)
			(layer "F.Fab")
		)
		(fp_line
			(start -0.12065 -0.2794)
			(end 0.12065 -0.2794)
			(stroke
				(width 0.1)
				(type default)
			)
			(layer "F.Fab")
		)
		(fp_line
			(start 0.120396 0.2794)
			(end -0.12065 0.2794)
			(stroke
				(width 0.1)
				(type default)
			)
			(layer "F.Fab")
		)
		(fp_line
			(start -0.12065 0.2794)
			(end -0.12065 0.3048)
			(stroke
				(width 0.1)
				(type default)
			)
			(layer "F.Fab")
		)
		(fp_line
			(start 0.67945 0.3048)
			(end 0.120396 0.3048)
			(stroke
				(width 0.1)
				(type default)
			)
			(layer "F.Fab")
		)
		(fp_line
			(start 0.120396 0.3048)
			(end 0.120396 0.2794)
			(stroke
				(width 0.1)
				(type default)
			)
			(layer "F.Fab")
		)
		(fp_line
			(start -0.12065 0.3048)
			(end -0.67945 0.3048)
			(stroke
				(width 0.1)
				(type default)
			)
			(layer "F.Fab")
		)
		(fp_line
			(start -0.67945 0.3048)
			(end -0.67945 -0.305054)
			(stroke
				(width 0.1)
				(type default)
			)
			(layer "F.Fab")
		)
		(pad "1" smd circle
			(at -0.40005 0 90)
			(size 0 0)
			(layers "F.Cu" "F.Mask" "F.Paste")
			(net "P12V_SSD0")
		)
		(pad "2" smd circle
			(at 0.40005 0 90)
			(size 0 0)
			(layers "F.Cu" "F.Mask" "F.Paste")
			(net "GND")
		)
	)
)
